(kicad_pcb
	(version 20260206)
	(generator "pcbnew")
	(generator_version "10.0")
	(general
		(thickness 1.6)
		(legacy_teardrops no)
	)
	(paper "A4")
	(title_block
		(title "panther-plus-userver — 13130-1b_20150205.brd")
		(comment 1 "Honey Badger (Wiwynn) / footprints 880-887 of 1509")
	)
	(layers
		(0 "F.Cu" signal "TOP")
		(4 "In1.Cu" signal "L2")
		(6 "In2.Cu" signal "L3")
		(8 "In3.Cu" signal "L4")
		(10 "In4.Cu" signal "L5")
		(12 "In5.Cu" signal "L6")
		(14 "In6.Cu" signal "L7")
		(16 "In7.Cu" signal "L8")
		(18 "In8.Cu" signal "L9")
		(20 "In9.Cu" signal "L10")
		(22 "In10.Cu" signal "L11")
		(2 "B.Cu" signal "BOTTOM")
		(9 "F.Adhes" user "F.Adhesive")
		(11 "B.Adhes" user "B.Adhesive")
		(13 "F.Paste" user "Package Geometry/Pastemask Top")
		(15 "B.Paste" user "Package Geometry/Pastemask Bottom")
		(5 "F.SilkS" user "Ref Des/Silkscreen Top")
		(7 "B.SilkS" user "Ref Des/Silkscreen Bottom")
		(1 "F.Mask" user "Board Geometry/Soldermask Top")
		(3 "B.Mask" user "Board Geometry/Soldermask Bottom")
		(17 "Dwgs.User" user "User.Drawings")
		(19 "Cmts.User" user "User.Comments")
		(21 "Eco1.User" user "User.Eco1")
		(23 "Eco2.User" user "User.Eco2")
		(25 "Edge.Cuts" user "Board Geometry/Outline")
		(27 "Margin" user)
		(31 "F.CrtYd" user "Package Geometry/Place Bound Top")
		(29 "B.CrtYd" user "Package Geometry/Place Bound Bottom")
		(35 "F.Fab" user "Ref Des/Assembly Top")
		(33 "B.Fab" user "Ref Des/Assembly Bottom")
	)
	(footprint ""
		(layer "B.Cu")
		(at 85.217 -31.75 90)
		(property "Reference" "R357"
			(at 0 0 90)
			(layer "B.SilkS")
			(hide yes)
			(effects
				(font
					(size 1.27 1.27)
				)
				(justify mirror)
			)
		)
		(property "Value" "402R2F-GP"
			(at -0.064008 -3.993896 90)
			(unlocked yes)
			(layer "B.Fab")
			(hide yes)
			(effects
				(font
					(size 1.016 1.016)
					(thickness 0.1524)
				)
				(justify mirror)
			)
		)
		(property "Device Type" "R402H16"
			(at -0.064008 -5.517896 90)
			(unlocked yes)
			(layer "B.Fab")
			(hide yes)
			(effects
				(font
					(size 1.016 1.016)
					(thickness 0.1524)
				)
				(justify mirror)
			)
		)
		(duplicate_pad_numbers_are_jumpers no)
		(fp_rect
			(start 0.381 0.8382)
			(end -0.381 -0.8382)
			(stroke
				(width 0)
				(type default)
			)
			(fill no)
			(layer "B.CrtYd")
		)
		(fp_rect
			(start 0.381 0.8382)
			(end -0.381 -0.8382)
			(stroke
				(width 0)
				(type default)
			)
			(fill no)
			(layer "B.Fab")
		)
		(pad "1" smd custom
			(at 0 -0.4318 270)
			(size 0.127 0.127)
			(layers "B.Cu" "B.Mask" "B.Paste")
			(net "SATA3_OBS_P")
			(options
				(clearance outline)
				(anchor circle)
			)
			(primitives
				(gr_poly
					(pts
						(arc
							(start -0.2032 0.2794)
							(mid -0.239121 0.264521)
							(end -0.254 0.2286)
						)
						(arc
							(start -0.254 -0.2286)
							(mid -0.239121 -0.264521)
							(end -0.2032 -0.2794)
						)
						(arc
							(start 0.2032 -0.2794)
							(mid 0.239121 -0.264521)
							(end 0.254 -0.2286)
						)
						(arc
							(start 0.254 0.2286)
							(mid 0.239121 0.264521)
							(end 0.2032 0.2794)
						)
					)
					(width 0)
					(fill yes)
				)
			)
		)
		(pad "2" smd custom
			(at 0 0.4318 270)
			(size 0.127 0.127)
			(layers "B.Cu" "B.Mask" "B.Paste")
			(net "SATA3_OBS_N")
			(options
				(clearance outline)
				(anchor circle)
			)
			(primitives
				(gr_poly
					(pts
						(arc
							(start -0.2032 0.2794)
							(mid -0.239121 0.264521)
							(end -0.254 0.2286)
						)
						(arc
							(start -0.254 -0.2286)
							(mid -0.239121 -0.264521)
							(end -0.2032 -0.2794)
						)
						(arc
							(start 0.2032 -0.2794)
							(mid 0.239121 -0.264521)
							(end 0.254 -0.2286)
						)
						(arc
							(start 0.254 0.2286)
							(mid 0.239121 0.264521)
							(end 0.2032 0.2794)
						)
					)
					(width 0)
					(fill yes)
				)
			)
		)
	)
	(footprint ""
		(layer "B.Cu")
		(at 70.2056 -17.272 90)
		(property "Reference" "PC123"
			(at 0 0 90)
			(layer "B.SilkS")
			(hide yes)
			(effects
				(font
					(size 1.27 1.27)
				)
				(justify mirror)
			)
		)
		(property "Value" "SC22U6D3V5MX-2GP"
			(at 0 -4.9022 90)
			(unlocked yes)
			(layer "B.Fab")
			(hide yes)
			(effects
				(font
					(size 1.016 1.016)
					(thickness 0.1524)
				)
				(justify mirror)
			)
		)
		(property "Device Type" "C805H58"
			(at 0 -6.8072 90)
			(unlocked yes)
			(layer "B.Fab")
			(hide yes)
			(effects
				(font
					(size 1.016 1.016)
					(thickness 0.1524)
				)
				(justify mirror)
			)
		)
		(duplicate_pad_numbers_are_jumpers no)
		(fp_line
			(start -0.6096 0)
			(end 0.6096 0)
			(stroke
				(width 0.3048)
				(type default)
			)
			(layer "B.SilkS")
		)
		(fp_poly
			(pts
				(xy 0.9017 1.4351) (xy -0.9017 1.4351) (xy -0.9017 -1.4351) (xy 0.9017 -1.4351)
			)
			(stroke
				(width 0)
				(type default)
			)
			(fill no)
			(layer "B.CrtYd")
		)
		(fp_poly
			(pts
				(xy -0.9017 1.4351) (xy -0.9017 -1.4351) (xy 0.9017 -1.4351) (xy 0.9017 1.4351)
			)
			(stroke
				(width 0)
				(type default)
			)
			(fill no)
			(layer "B.Fab")
		)
		(pad "1" smd rect
			(at 0 -0.8382 270)
			(size 1.5494 0.9398)
			(layers "B.Cu" "B.Mask" "B.Paste")
			(net "P1V8_STBY_VOUT")
		)
		(pad "2" smd rect
			(at 0 0.8382 270)
			(size 1.5494 0.9398)
			(layers "B.Cu" "B.Mask" "B.Paste")
			(net "GND")
		)
	)
	(footprint ""
		(layer "B.Cu")
		(at 140.462 -47.625 -90)
		(property "Reference" "R297"
			(at 0 0 90)
			(layer "B.SilkS")
			(hide yes)
			(effects
				(font
					(size 1.27 1.27)
				)
				(justify mirror)
			)
		)
		(property "Value" "0R2J-2-GP"
			(at -1.7907 -1.1176 270)
			(unlocked yes)
			(layer "B.Fab")
			(hide yes)
			(effects
				(font
					(size 1.016 1.016)
					(thickness 0.1524)
				)
				(justify mirror)
			)
		)
		(property "Device Type" "R402H16"
			(at -1.7907 -2.6416 270)
			(unlocked yes)
			(layer "B.Fab")
			(hide yes)
			(effects
				(font
					(size 1.016 1.016)
					(thickness 0.1524)
				)
				(justify mirror)
			)
		)
		(duplicate_pad_numbers_are_jumpers no)
		(fp_rect
			(start 0.381 0.8382)
			(end -0.381 -0.8382)
			(stroke
				(width 0)
				(type default)
			)
			(fill no)
			(layer "B.CrtYd")
		)
		(fp_rect
			(start 0.381 0.8382)
			(end -0.381 -0.8382)
			(stroke
				(width 0)
				(type default)
			)
			(fill no)
			(layer "B.Fab")
		)
		(pad "1" smd custom
			(at 0 -0.4318 90)
			(size 0.127 0.127)
			(layers "B.Cu" "B.Mask" "B.Paste")
			(net "C_NCE_R#")
			(options
				(clearance outline)
				(anchor circle)
			)
			(primitives
				(gr_poly
					(pts
						(arc
							(start -0.2032 0.2794)
							(mid -0.239121 0.264521)
							(end -0.254 0.2286)
						)
						(arc
							(start -0.254 -0.2286)
							(mid -0.239121 -0.264521)
							(end -0.2032 -0.2794)
						)
						(arc
							(start 0.2032 -0.2794)
							(mid 0.239121 -0.264521)
							(end 0.254 -0.2286)
						)
						(arc
							(start 0.254 0.2286)
							(mid 0.239121 0.264521)
							(end 0.2032 0.2794)
						)
					)
					(width 0)
					(fill yes)
				)
			)
		)
		(pad "2" smd custom
			(at 0 0.4318 90)
			(size 0.127 0.127)
			(layers "B.Cu" "B.Mask" "B.Paste")
			(net "C_NCE#")
			(options
				(clearance outline)
				(anchor circle)
			)
			(primitives
				(gr_poly
					(pts
						(arc
							(start -0.2032 0.2794)
							(mid -0.239121 0.264521)
							(end -0.254 0.2286)
						)
						(arc
							(start -0.254 -0.2286)
							(mid -0.239121 -0.264521)
							(end -0.2032 -0.2794)
						)
						(arc
							(start 0.2032 -0.2794)
							(mid 0.239121 -0.264521)
							(end 0.254 -0.2286)
						)
						(arc
							(start 0.254 0.2286)
							(mid 0.239121 0.264521)
							(end 0.2032 0.2794)
						)
					)
					(width 0)
					(fill yes)
				)
			)
		)
	)
	(footprint ""
		(layer "B.Cu")
		(at 98.679 -51.435 180)
		(property "Reference" "R279"
			(at 0 0 0)
			(layer "B.SilkS")
			(hide yes)
			(effects
				(font
					(size 1.27 1.27)
				)
				(justify mirror)
			)
		)
		(property "Value" "23D7R2F-GP"
			(at -0.064008 -3.993896 180)
			(unlocked yes)
			(layer "B.Fab")
			(hide yes)
			(effects
				(font
					(size 1.016 1.016)
					(thickness 0.1524)
				)
				(justify mirror)
			)
		)
		(property "Device Type" "R402H16"
			(at -0.064008 -5.517896 180)
			(unlocked yes)
			(layer "B.Fab")
			(hide yes)
			(effects
				(font
					(size 1.016 1.016)
					(thickness 0.1524)
				)
				(justify mirror)
			)
		)
		(duplicate_pad_numbers_are_jumpers no)
		(fp_rect
			(start 0.381 0.8382)
			(end -0.381 -0.8382)
			(stroke
				(width 0)
				(type default)
			)
			(fill no)
			(layer "B.CrtYd")
		)
		(fp_rect
			(start 0.381 0.8382)
			(end -0.381 -0.8382)
			(stroke
				(width 0)
				(type default)
			)
			(fill no)
			(layer "B.Fab")
		)
		(pad "1" smd custom
			(at 0 -0.4318)
			(size 0.127 0.127)
			(layers "B.Cu" "B.Mask" "B.Paste")
			(net "M_A_CMDPU")
			(options
				(clearance outline)
				(anchor circle)
			)
			(primitives
				(gr_poly
					(pts
						(arc
							(start -0.2032 0.2794)
							(mid -0.239121 0.264521)
							(end -0.254 0.2286)
						)
						(arc
							(start -0.254 -0.2286)
							(mid -0.239121 -0.264521)
							(end -0.2032 -0.2794)
						)
						(arc
							(start 0.2032 -0.2794)
							(mid 0.239121 -0.264521)
							(end 0.254 -0.2286)
						)
						(arc
							(start 0.254 0.2286)
							(mid 0.239121 0.264521)
							(end 0.2032 0.2794)
						)
					)
					(width 0)
					(fill yes)
				)
			)
		)
		(pad "2" smd custom
			(at 0 0.4318)
			(size 0.127 0.127)
			(layers "B.Cu" "B.Mask" "B.Paste")
			(net "GND")
			(options
				(clearance outline)
				(anchor circle)
			)
			(primitives
				(gr_poly
					(pts
						(arc
							(start -0.2032 0.2794)
							(mid -0.239121 0.264521)
							(end -0.254 0.2286)
						)
						(arc
							(start -0.254 -0.2286)
							(mid -0.239121 -0.264521)
							(end -0.2032 -0.2794)
						)
						(arc
							(start 0.2032 -0.2794)
							(mid 0.239121 -0.264521)
							(end 0.254 -0.2286)
						)
						(arc
							(start 0.254 0.2286)
							(mid 0.239121 0.264521)
							(end 0.2032 0.2794)
						)
					)
					(width 0)
					(fill yes)
				)
			)
		)
	)
	(footprint ""
		(layer "B.Cu")
		(at 190.881 -27.94)
		(property "Reference" "PR154"
			(at 0 0 0)
			(layer "B.SilkS")
			(hide yes)
			(effects
				(font
					(size 1.27 1.27)
				)
				(justify mirror)
			)
		)
		(property "Value" "0R2J-2-GP"
			(at -1.7907 -1.1176 0)
			(unlocked yes)
			(layer "B.Fab")
			(hide yes)
			(effects
				(font
					(size 1.016 1.016)
					(thickness 0.1524)
				)
				(justify mirror)
			)
		)
		(property "Device Type" "R402H16"
			(at -1.7907 -2.6416 0)
			(unlocked yes)
			(layer "B.Fab")
			(hide yes)
			(effects
				(font
					(size 1.016 1.016)
					(thickness 0.1524)
				)
				(justify mirror)
			)
		)
		(duplicate_pad_numbers_are_jumpers no)
		(fp_rect
			(start 0.381 0.8382)
			(end -0.381 -0.8382)
			(stroke
				(width 0)
				(type default)
			)
			(fill no)
			(layer "B.CrtYd")
		)
		(fp_rect
			(start 0.381 0.8382)
			(end -0.381 -0.8382)
			(stroke
				(width 0)
				(type default)
			)
			(fill no)
			(layer "B.Fab")
		)
		(pad "1" smd custom
			(at 0 -0.4318 180)
			(size 0.127 0.127)
			(layers "B.Cu" "B.Mask" "B.Paste")
			(net "VR_PVDDR_A_VDD")
			(options
				(clearance outline)
				(anchor circle)
			)
			(primitives
				(gr_poly
					(pts
						(arc
							(start -0.2032 0.2794)
							(mid -0.239121 0.264521)
							(end -0.254 0.2286)
						)
						(arc
							(start -0.254 -0.2286)
							(mid -0.239121 -0.264521)
							(end -0.2032 -0.2794)
						)
						(arc
							(start 0.2032 -0.2794)
							(mid 0.239121 -0.264521)
							(end 0.254 -0.2286)
						)
						(arc
							(start 0.254 0.2286)
							(mid 0.239121 0.264521)
							(end 0.2032 0.2794)
						)
					)
					(width 0)
					(fill yes)
				)
			)
		)
		(pad "2" smd custom
			(at 0 0.4318 180)
			(size 0.127 0.127)
			(layers "B.Cu" "B.Mask" "B.Paste")
			(net "VDDR_5VBIAS")
			(options
				(clearance outline)
				(anchor circle)
			)
			(primitives
				(gr_poly
					(pts
						(arc
							(start -0.2032 0.2794)
							(mid -0.239121 0.264521)
							(end -0.254 0.2286)
						)
						(arc
							(start -0.254 -0.2286)
							(mid -0.239121 -0.264521)
							(end -0.2032 -0.2794)
						)
						(arc
							(start 0.2032 -0.2794)
							(mid 0.239121 -0.264521)
							(end 0.254 -0.2286)
						)
						(arc
							(start 0.254 0.2286)
							(mid 0.239121 0.264521)
							(end 0.2032 0.2794)
						)
					)
					(width 0)
					(fill yes)
				)
			)
		)
	)
	(footprint ""
		(layer "B.Cu")
		(at 34.2392 -12.7)
		(property "Reference" "C268"
			(at 0 0 0)
			(layer "B.SilkS")
			(hide yes)
			(effects
				(font
					(size 1.27 1.27)
				)
				(justify mirror)
			)
		)
		(property "Value" "SCD1U16V2KX-3GP"
			(at -1.1811 -2.7051 0)
			(unlocked yes)
			(layer "B.Fab")
			(hide yes)
			(effects
				(font
					(size 1.016 1.016)
					(thickness 0.1524)
				)
				(justify mirror)
			)
		)
		(property "Device Type" "C402H22"
			(at -1.1811 -4.2291 0)
			(unlocked yes)
			(layer "B.Fab")
			(hide yes)
			(effects
				(font
					(size 1.016 1.016)
					(thickness 0.1524)
				)
				(justify mirror)
			)
		)
		(duplicate_pad_numbers_are_jumpers no)
		(fp_rect
			(start 0.381 0.7366)
			(end -0.381 -0.7366)
			(stroke
				(width 0)
				(type default)
			)
			(fill no)
			(layer "B.CrtYd")
		)
		(fp_rect
			(start 0.381 0.7366)
			(end -0.381 -0.7366)
			(stroke
				(width 0)
				(type default)
			)
			(fill no)
			(layer "B.Fab")
		)
		(pad "1" smd custom
			(at 0 -0.4572 180)
			(size 0.1143 0.1143)
			(layers "B.Cu" "B.Mask" "B.Paste")
			(net "P2E_CPU_SAS_C_TX_DP7")
			(options
				(clearance outline)
				(anchor circle)
			)
			(primitives
				(gr_poly
					(pts
						(arc
							(start -0.254 0.1778)
							(mid -0.239121 0.213721)
							(end -0.2032 0.2286)
						)
						(arc
							(start 0.2032 0.2286)
							(mid 0.239121 0.213721)
							(end 0.254 0.1778)
						)
						(arc
							(start 0.254 -0.1778)
							(mid 0.239121 -0.213721)
							(end 0.2032 -0.2286)
						)
						(arc
							(start -0.2032 -0.2286)
							(mid -0.239121 -0.213721)
							(end -0.254 -0.1778)
						)
					)
					(width 0)
					(fill yes)
				)
			)
		)
		(pad "2" smd custom
			(at 0 0.4572 180)
			(size 0.1143 0.1143)
			(layers "B.Cu" "B.Mask" "B.Paste")
			(net "P2E_CPU_SAS_TX_DP7")
			(options
				(clearance outline)
				(anchor circle)
			)
			(primitives
				(gr_poly
					(pts
						(arc
							(start -0.254 0.1778)
							(mid -0.239121 0.213721)
							(end -0.2032 0.2286)
						)
						(arc
							(start 0.2032 0.2286)
							(mid 0.239121 0.213721)
							(end 0.254 0.1778)
						)
						(arc
							(start 0.254 -0.1778)
							(mid 0.239121 -0.213721)
							(end 0.2032 -0.2286)
						)
						(arc
							(start -0.2032 -0.2286)
							(mid -0.239121 -0.213721)
							(end -0.254 -0.1778)
						)
					)
					(width 0)
					(fill yes)
				)
			)
		)
	)
	(footprint ""
		(layer "B.Cu")
		(at 139.446 -45.466 -90)
		(property "Reference" "C172"
			(at 0 0 90)
			(layer "B.SilkS")
			(hide yes)
			(effects
				(font
					(size 1.27 1.27)
				)
				(justify mirror)
			)
		)
		(property "Value" "SCD1U10V2KX-5GP"
			(at -1.1811 -2.7051 270)
			(unlocked yes)
			(layer "B.Fab")
			(hide yes)
			(effects
				(font
					(size 1.016 1.016)
					(thickness 0.1524)
				)
				(justify mirror)
			)
		)
		(property "Device Type" "C402H22"
			(at -1.1811 -4.2291 270)
			(unlocked yes)
			(layer "B.Fab")
			(hide yes)
			(effects
				(font
					(size 1.016 1.016)
					(thickness 0.1524)
				)
				(justify mirror)
			)
		)
		(duplicate_pad_numbers_are_jumpers no)
		(fp_rect
			(start 0.381 0.7366)
			(end -0.381 -0.7366)
			(stroke
				(width 0)
				(type default)
			)
			(fill no)
			(layer "B.CrtYd")
		)
		(fp_rect
			(start 0.381 0.7366)
			(end -0.381 -0.7366)
			(stroke
				(width 0)
				(type default)
			)
			(fill no)
			(layer "B.Fab")
		)
		(pad "1" smd custom
			(at 0 -0.4572 90)
			(size 0.1143 0.1143)
			(layers "B.Cu" "B.Mask" "B.Paste")
			(net "P3V3_STBY")
			(options
				(clearance outline)
				(anchor circle)
			)
			(primitives
				(gr_poly
					(pts
						(arc
							(start -0.254 0.1778)
							(mid -0.239121 0.213721)
							(end -0.2032 0.2286)
						)
						(arc
							(start 0.2032 0.2286)
							(mid 0.239121 0.213721)
							(end 0.254 0.1778)
						)
						(arc
							(start 0.254 -0.1778)
							(mid 0.239121 -0.213721)
							(end 0.2032 -0.2286)
						)
						(arc
							(start -0.2032 -0.2286)
							(mid -0.239121 -0.213721)
							(end -0.254 -0.1778)
						)
					)
					(width 0)
					(fill yes)
				)
			)
		)
		(pad "2" smd custom
			(at 0 0.4572 90)
			(size 0.1143 0.1143)
			(layers "B.Cu" "B.Mask" "B.Paste")
			(net "GND")
			(options
				(clearance outline)
				(anchor circle)
			)
			(primitives
				(gr_poly
					(pts
						(arc
							(start -0.254 0.1778)
							(mid -0.239121 0.213721)
							(end -0.2032 0.2286)
						)
						(arc
							(start 0.2032 0.2286)
							(mid 0.239121 0.213721)
							(end 0.254 0.1778)
						)
						(arc
							(start 0.254 -0.1778)
							(mid 0.239121 -0.213721)
							(end 0.2032 -0.2286)
						)
						(arc
							(start -0.2032 -0.2286)
							(mid -0.239121 -0.213721)
							(end -0.254 -0.1778)
						)
					)
					(width 0)
					(fill yes)
				)
			)
		)
	)
	(footprint ""
		(layer "B.Cu")
		(at 187.96 -59.944)
		(property "Reference" "C352"
			(at 0 0 0)
			(layer "B.SilkS")
			(hide yes)
			(effects
				(font
					(size 1.27 1.27)
				)
				(justify mirror)
			)
		)
		(property "Value" "SC1U6D3V3KX-2GP"
			(at 0.0254 -2.0193 0)
			(unlocked yes)
			(layer "B.Fab")
			(hide yes)
			(effects
				(font
					(size 1.016 1.016)
					(thickness 0.1524)
				)
				(justify mirror)
			)
		)
		(property "Device Type" "C603H36"
			(at 0.0254 -3.5433 0)
			(unlocked yes)
			(layer "B.Fab")
			(hide yes)
			(effects
				(font
					(size 1.016 1.016)
					(thickness 0.1524)
				)
				(justify mirror)
			)
		)
		(duplicate_pad_numbers_are_jumpers no)
		(fp_line
			(start 0.4064 0)
			(end -0.4064 0)
			(stroke
				(width 0.2286)
				(type default)
			)
			(layer "B.SilkS")
		)
		(fp_rect
			(start 0.635 1.1811)
			(end -0.635 -1.1811)
			(stroke
				(width 0)
				(type default)
			)
			(fill no)
			(layer "B.CrtYd")
		)
		(fp_rect
			(start 0.635 1.1811)
			(end -0.635 -1.1811)
			(stroke
				(width 0)
				(type default)
			)
			(fill no)
			(layer "B.Fab")
		)
		(pad "1" smd custom
			(at 0 -0.6604 180)
			(size 0.19685 0.19685)
			(layers "B.Cu" "B.Mask" "B.Paste")
			(net "DDR3_M_A_VREF_DQ0")
			(options
				(clearance outline)
				(anchor circle)
			)
			(primitives
				(gr_poly
					(pts
						(arc
							(start 0.508 0.2921)
							(mid 0.478242 0.363942)
							(end 0.4064 0.3937)
						)
						(arc
							(start -0.4064 0.3937)
							(mid -0.478242 0.363942)
							(end -0.508 0.2921)
						)
						(arc
							(start -0.508 -0.2921)
							(mid -0.478242 -0.363942)
							(end -0.4064 -0.3937)
						)
						(arc
							(start 0.4064 -0.3937)
							(mid 0.478242 -0.363942)
							(end 0.508 -0.2921)
						)
					)
					(width 0)
					(fill yes)
				)
			)
		)
		(pad "2" smd custom
			(at 0 0.6604 180)
			(size 0.19685 0.19685)
			(layers "B.Cu" "B.Mask" "B.Paste")
			(net "GND")
			(options
				(clearance outline)
				(anchor circle)
			)
			(primitives
				(gr_poly
					(pts
						(arc
							(start 0.508 0.2921)
							(mid 0.478242 0.363942)
							(end 0.4064 0.3937)
						)
						(arc
							(start -0.4064 0.3937)
							(mid -0.478242 0.363942)
							(end -0.508 0.2921)
						)
						(arc
							(start -0.508 -0.2921)
							(mid -0.478242 -0.363942)
							(end -0.4064 -0.3937)
						)
						(arc
							(start 0.4064 -0.3937)
							(mid 0.478242 -0.363942)
							(end 0.508 -0.2921)
						)
					)
					(width 0)
					(fill yes)
				)
			)
		)
	)
)
